(kicad_pcb
	(version 20260206)
	(generator "pcbnew")
	(generator_version "10.0")
	(general
		(thickness 1.6)
		(legacy_teardrops no)
	)
	(paper "A4")
	(title_block
		(title "04192023_DAF0TMB3IC0_F0TG_MB_C_brd_V02_OCP.brd")
		(comment 1 "Grand Teton / footprint 1669 of 8354 (U18), pads 320-426 of 484")
	)
	(layers
		(0 "F.Cu" signal "TOP")
		(4 "In1.Cu" signal "GND")
		(6 "In2.Cu" signal "IN1")
		(8 "In3.Cu" signal "GND1")
		(10 "In4.Cu" signal "IN2")
		(12 "In5.Cu" signal "GND2")
		(14 "In6.Cu" signal "IN3")
		(16 "In7.Cu" signal "GND3")
		(18 "In8.Cu" signal "VCC")
		(20 "In9.Cu" signal "VCC1")
		(22 "In10.Cu" signal "GND4")
		(24 "In11.Cu" signal "IN4")
		(26 "In12.Cu" signal "GND5")
		(28 "In13.Cu" signal "IN5")
		(30 "In14.Cu" signal "GND6")
		(32 "In15.Cu" signal "IN6")
		(34 "In16.Cu" signal "GND7")
		(2 "B.Cu" signal "BOTTOM")
		(9 "F.Adhes" user "F.Adhesive")
		(11 "B.Adhes" user "B.Adhesive")
		(13 "F.Paste" user "Package Geometry/Pastemask Top")
		(15 "B.Paste" user "Package Geometry/Pastemask Bottom")
		(5 "F.SilkS" user "Ref Des/Silkscreen Top")
		(7 "B.SilkS" user "Ref Des/Silkscreen Bottom")
		(1 "F.Mask" user "Board Geometry/Soldermask Top")
		(3 "B.Mask" user "Board Geometry/Soldermask Bottom")
		(17 "Dwgs.User" user "User.Drawings")
		(19 "Cmts.User" user "User.Comments")
		(21 "Eco1.User" user "User.Eco1")
		(23 "Eco2.User" user "User.Eco2")
		(25 "Edge.Cuts" user "Board Geometry/Outline")
		(27 "Margin" user)
		(31 "F.CrtYd" user "Package Geometry/Place Bound Top")
		(29 "B.CrtYd" user "Package Geometry/Place Bound Bottom")
		(35 "F.Fab" user "Ref Des/Assembly Top")
		(33 "B.Fab" user "Ref Des/Assembly Bottom")
	)
	(footprint ""
		(layer "F.Cu")
		(at 185.522108 -115.052856 90)
		(property "Reference" "U18"
			(at -10.68451 -12.951206 0)
			(unlocked yes)
			(layer "F.SilkS")
			(effects
				(font
					(size 0.7874 0.5842)
					(thickness 0.1524)
				)
				(justify left)
			)
		)
		(property "Value" ""
			(at 0 0 90)
			(layer "F.Fab")
			(effects
				(font
					(size 1.27 1.27)
				)
			)
		)
		(duplicate_pad_numbers_are_jumpers no)
		(pad "N12" smd circle
			(at 0.40005 1.199896 90)
			(size 0.4064 0.4064)
			(layers "F.Cu" "F.Mask" "F.Paste")
			(net "P3V3_AUX")
		)
		(pad "N13" smd circle
			(at 1.199896 1.199896 90)
			(size 0.4064 0.4064)
			(layers "F.Cu" "F.Mask" "F.Paste")
			(net "P3V3_AUX")
		)
		(pad "N14" smd circle
			(at 1.999996 1.199896 90)
			(size 0.4064 0.4064)
			(layers "F.Cu" "F.Mask" "F.Paste")
			(net "GND")
		)
		(pad "N15" smd circle
			(at 2.800096 1.199896 90)
			(size 0.4064 0.4064)
			(layers "F.Cu" "F.Mask" "F.Paste")
			(net "P1V8_AUX")
		)
		(pad "N16" smd circle
			(at 3.599942 1.199896 90)
			(size 0.4064 0.4064)
			(layers "F.Cu" "F.Mask" "F.Paste")
			(net "FM_CPU1_SMERR_N")
		)
		(pad "N17" smd circle
			(at 4.400042 1.199896 90)
			(size 0.4064 0.4064)
			(layers "F.Cu" "F.Mask" "F.Paste")
			(net "FM_ESPI_CPU0_ALERT_SEL")
		)
		(pad "N18" smd circle
			(at 5.199888 1.199896 90)
			(size 0.4064 0.4064)
			(layers "F.Cu" "F.Mask" "F.Paste")
			(net "RST_RT_CPU0_P2_PERST_R2_N")
		)
		(pad "N19" smd circle
			(at 5.999988 1.199896 90)
			(size 0.4064 0.4064)
			(layers "F.Cu" "F.Mask" "F.Paste")
			(net "PWRGD_P12V_MEM_R")
		)
		(pad "N20" smd circle
			(at 6.800088 1.199896 90)
			(size 0.4064 0.4064)
			(layers "F.Cu" "F.Mask" "F.Paste")
			(net "TP_PWRGD_P12V_FAN_DR_R")
		)
		(pad "N21" smd circle
			(at 7.599934 1.199896 90)
			(size 0.4064 0.4064)
			(layers "F.Cu" "F.Mask" "F.Paste")
			(net "GND")
		)
		(pad "N22" smd circle
			(at 8.400034 1.199896 90)
			(size 0.4064 0.4064)
			(layers "F.Cu" "F.Mask" "F.Paste")
			(net "BIOS_DEBUG_MODE_R")
		)
		(pad "P1" smd circle
			(at -8.400034 1.999996 90)
			(size 0.4064 0.4064)
			(layers "F.Cu" "F.Mask" "F.Paste")
			(net "OCP_V3_2_P3V3_P12V_ADC_ALERT")
		)
		(pad "P2" smd circle
			(at -7.599934 1.999996 90)
			(size 0.4064 0.4064)
			(layers "F.Cu" "F.Mask" "F.Paste")
			(net "FM_SMB_RST_E1S_0_N")
		)
		(pad "P3" smd circle
			(at -6.800088 1.999996 90)
			(size 0.4064 0.4064)
			(layers "F.Cu" "F.Mask" "F.Paste")
			(net "FM_CPU0_CORETYPE2")
		)
		(pad "P4" smd circle
			(at -5.999988 1.999996 90)
			(size 0.4064 0.4064)
			(layers "F.Cu" "F.Mask" "F.Paste")
			(net "FM_CPU1_CORETYPE0")
		)
		(pad "P5" smd circle
			(at -5.199888 1.999996 90)
			(size 0.4064 0.4064)
			(layers "F.Cu" "F.Mask" "F.Paste")
			(net "FM_APML_MUX2_SEL_R")
		)
		(pad "P6" smd circle
			(at -4.400042 1.999996 90)
			(size 0.4064 0.4064)
			(layers "F.Cu" "F.Mask" "F.Paste")
			(net "FM_APML_MUX2_OE_R_N")
		)
		(pad "P7" smd circle
			(at -3.599942 1.999996 90)
			(size 0.4064 0.4064)
			(layers "F.Cu" "F.Mask" "F.Paste")
			(net "FM_PVDDCR_CPU1_P0_R_EN")
		)
		(pad "P8" smd circle
			(at -2.800096 1.999996 90)
			(size 0.4064 0.4064)
			(layers "F.Cu" "F.Mask" "F.Paste")
			(net "P3V3_AUX")
		)
		(pad "P9" smd circle
			(at -1.999996 1.999996 90)
			(size 0.4064 0.4064)
			(layers "F.Cu" "F.Mask" "F.Paste")
			(net "GND")
		)
		(pad "P10" smd circle
			(at -1.199896 1.999996 90)
			(size 0.4064 0.4064)
			(layers "F.Cu" "F.Mask" "F.Paste")
			(net "GND")
		)
		(pad "P11" smd circle
			(at -0.40005 1.999996 90)
			(size 0.4064 0.4064)
			(layers "F.Cu" "F.Mask" "F.Paste")
			(net "GND")
		)
		(pad "P12" smd circle
			(at 0.40005 1.999996 90)
			(size 0.4064 0.4064)
			(layers "F.Cu" "F.Mask" "F.Paste")
			(net "GND")
		)
		(pad "P13" smd circle
			(at 1.199896 1.999996 90)
			(size 0.4064 0.4064)
			(layers "F.Cu" "F.Mask" "F.Paste")
			(net "GND")
		)
		(pad "P14" smd circle
			(at 1.999996 1.999996 90)
			(size 0.4064 0.4064)
			(layers "F.Cu" "F.Mask" "F.Paste")
			(net "GND")
		)
		(pad "P15" smd circle
			(at 2.800096 1.999996 90)
			(size 0.4064 0.4064)
			(layers "F.Cu" "F.Mask" "F.Paste")
			(net "P1V8_AUX")
		)
		(pad "P16" smd circle
			(at 3.599942 1.999996 90)
			(size 0.4064 0.4064)
			(layers "F.Cu" "F.Mask" "F.Paste")
			(net "FM_HDT_HDR_PWROK")
		)
		(pad "P17" smd circle
			(at 4.400042 1.999996 90)
			(size 0.4064 0.4064)
			(layers "F.Cu" "F.Mask" "F.Paste")
			(net "ESPI_CPU0_R1_D3")
		)
		(pad "P18" smd circle
			(at 5.199888 1.999996 90)
			(size 0.4064 0.4064)
			(layers "F.Cu" "F.Mask" "F.Paste")
			(net "ESPI_CPU0_R1_D2")
		)
		(pad "P19" smd circle
			(at 5.999988 1.999996 90)
			(size 0.4064 0.4064)
			(layers "F.Cu" "F.Mask" "F.Paste")
			(net "ESPI_CPU0_R1_D1")
		)
		(pad "P20" smd circle
			(at 6.800088 1.999996 90)
			(size 0.4064 0.4064)
			(layers "F.Cu" "F.Mask" "F.Paste")
			(net "ESPI_CPU0_ALERT_R_N")
		)
		(pad "P21" smd circle
			(at 7.599934 1.999996 90)
			(size 0.4064 0.4064)
			(layers "F.Cu" "F.Mask" "F.Paste")
			(net "FM_CPU0_HDT_CONN_TESTEN")
		)
		(pad "P22" smd circle
			(at 8.400034 1.999996 90)
			(size 0.4064 0.4064)
			(layers "F.Cu" "F.Mask" "F.Paste")
			(net "ESPI_CPU0_CS1_R_N")
		)
		(pad "R1" smd circle
			(at -8.400034 2.800096 90)
			(size 0.4064 0.4064)
			(layers "F.Cu" "F.Mask" "F.Paste")
			(net "FM_CPU0_CORETYPE0")
		)
		(pad "R2" smd circle
			(at -7.599934 2.800096 90)
			(size 0.4064 0.4064)
			(layers "F.Cu" "F.Mask" "F.Paste")
			(net "FM_CPU0_CORETYPE1")
		)
		(pad "R3" smd circle
			(at -6.800088 2.800096 90)
			(size 0.4064 0.4064)
			(layers "F.Cu" "F.Mask" "F.Paste")
			(net "FM_CPU1_SP5R1")
		)
		(pad "R4" smd circle
			(at -5.999988 2.800096 90)
			(size 0.4064 0.4064)
			(layers "F.Cu" "F.Mask" "F.Paste")
			(net "FM_CPU1_SP5R2")
		)
		(pad "R5" smd circle
			(at -5.199888 2.800096 90)
			(size 0.4064 0.4064)
			(layers "F.Cu" "F.Mask" "F.Paste")
			(net "FM_LED_PWRGD_PVDDCR_CPU1_P0")
		)
		(pad "R6" smd circle
			(at -4.400042 2.800096 90)
			(size 0.4064 0.4064)
			(layers "F.Cu" "F.Mask" "F.Paste")
			(net "PWRGD_CHAF_CPU1_R2")
		)
		(pad "R7" smd circle
			(at -3.599942 2.800096 90)
			(size 0.4064 0.4064)
			(layers "F.Cu" "F.Mask" "F.Paste")
			(net "FM_PWRGD_PVDDCR_CPU1_P0")
		)
		(pad "R8" smd circle
			(at -2.800096 2.800096 90)
			(size 0.4064 0.4064)
			(layers "F.Cu" "F.Mask" "F.Paste")
			(net "GND")
		)
		(pad "R9" smd circle
			(at -1.999996 2.800096 90)
			(size 0.4064 0.4064)
			(layers "F.Cu" "F.Mask" "F.Paste")
			(net "P3V3_AUX")
		)
		(pad "R10" smd circle
			(at -1.199896 2.800096 90)
			(size 0.4064 0.4064)
			(layers "F.Cu" "F.Mask" "F.Paste")
			(net "P3V3_AUX")
		)
		(pad "R11" smd circle
			(at -0.40005 2.800096 90)
			(size 0.4064 0.4064)
			(layers "F.Cu" "F.Mask" "F.Paste")
			(net "P3V3_AUX")
		)
		(pad "R12" smd circle
			(at 0.40005 2.800096 90)
			(size 0.4064 0.4064)
			(layers "F.Cu" "F.Mask" "F.Paste")
			(net "P3V3_AUX")
		)
		(pad "R13" smd circle
			(at 1.199896 2.800096 90)
			(size 0.4064 0.4064)
			(layers "F.Cu" "F.Mask" "F.Paste")
			(net "P3V3_AUX")
		)
		(pad "R14" smd circle
			(at 1.999996 2.800096 90)
			(size 0.4064 0.4064)
			(layers "F.Cu" "F.Mask" "F.Paste")
			(net "P3V3_AUX")
		)
		(pad "R15" smd circle
			(at 2.800096 2.800096 90)
			(size 0.4064 0.4064)
			(layers "F.Cu" "F.Mask" "F.Paste")
			(net "GND")
		)
		(pad "R16" smd circle
			(at 3.599942 2.800096 90)
			(size 0.4064 0.4064)
			(layers "F.Cu" "F.Mask" "F.Paste")
			(net "CPU1_JTAG_BUF_R_OE")
		)
		(pad "R17" smd circle
			(at 4.400042 2.800096 90)
			(size 0.4064 0.4064)
			(layers "F.Cu" "F.Mask" "F.Paste")
			(net "FM_PLD_CPU1_PRSNT_HDT")
		)
		(pad "R18" smd circle
			(at 5.199888 2.800096 90)
			(size 0.4064 0.4064)
			(layers "F.Cu" "F.Mask" "F.Paste")
			(net "CPU0_SPD_HOST_CTRL_R1_N")
		)
		(pad "R19" smd circle
			(at 5.999988 2.800096 90)
			(size 0.4064 0.4064)
			(layers "F.Cu" "F.Mask" "F.Paste")
			(net "SCM_USB_OC_R_N")
		)
		(pad "R20" smd circle
			(at 6.800088 2.800096 90)
			(size 0.4064 0.4064)
			(layers "F.Cu" "F.Mask" "F.Paste")
			(net "RST_RT_CPU0_P2_RESET_R2_N")
		)
		(pad "R21" smd circle
			(at 7.599934 2.800096 90)
			(size 0.4064 0.4064)
			(layers "F.Cu" "F.Mask" "F.Paste")
			(net "CLK_ESPI_CPU0_R1_CLK1")
		)
		(pad "R22" smd circle
			(at 8.400034 2.800096 90)
			(size 0.4064 0.4064)
			(layers "F.Cu" "F.Mask" "F.Paste")
			(net "FM_JTAG_BMC_OE")
		)
		(pad "T1" smd circle
			(at -8.400034 3.599942 90)
			(size 0.4064 0.4064)
			(layers "F.Cu" "F.Mask" "F.Paste")
			(net "FM_CPU1_CORETYPE1")
		)
		(pad "T2" smd circle
			(at -7.599934 3.599942 90)
			(size 0.4064 0.4064)
			(layers "F.Cu" "F.Mask" "F.Paste")
			(net "FM_CPU1_CORETYPE2")
		)
		(pad "T3" smd circle
			(at -6.800088 3.599942 90)
			(size 0.4064 0.4064)
			(layers "F.Cu" "F.Mask" "F.Paste")
			(net "FM_CPU1_SP5R3")
		)
		(pad "T4" smd circle
			(at -5.999988 3.599942 90)
			(size 0.4064 0.4064)
			(layers "F.Cu" "F.Mask" "F.Paste")
			(net "FM_CPU1_SP5R4")
		)
		(pad "T5" smd circle
			(at -5.199888 3.599942 90)
			(size 0.4064 0.4064)
			(layers "F.Cu" "F.Mask" "F.Paste")
			(net "FM_PDB_BUF_EN_N")
		)
		(pad "T6" smd circle
			(at -4.400042 3.599942 90)
			(size 0.4064 0.4064)
			(layers "F.Cu" "F.Mask" "F.Paste")
			(net "PWRGD_CHGL_CPU1_R2")
		)
		(pad "T7" smd circle
			(at -3.599942 3.599942 90)
			(size 0.4064 0.4064)
			(layers "F.Cu" "F.Mask" "F.Paste")
			(net "FM_PVDDCR_CPU1_P1_R_EN")
		)
		(pad "T8" smd circle
			(at -2.800096 3.599942 90)
			(size 0.4064 0.4064)
			(layers "F.Cu" "F.Mask" "F.Paste")
			(net "FM_PWRGD_PVDDCR_CPU1_P1")
		)
		(pad "T9" smd circle
			(at -1.999996 3.599942 90)
			(size 0.4064 0.4064)
			(layers "F.Cu" "F.Mask" "F.Paste")
			(net "FM_PWRGD_P1V8_RETIMER_CPU0")
		)
		(pad "T10" smd circle
			(at -1.199896 3.599942 90)
			(size 0.4064 0.4064)
			(layers "F.Cu" "F.Mask" "F.Paste")
			(net "FM_GPU_HSC_EN_R")
		)
		(pad "T11" smd circle
			(at -0.40005 3.599942 90)
			(size 0.4064 0.4064)
			(layers "F.Cu" "F.Mask" "F.Paste")
			(net "FM_LED_PWRGD_PVDD33_S5")
		)
		(pad "T12" smd circle
			(at 0.40005 3.599942 90)
			(size 0.4064 0.4064)
			(layers "F.Cu" "F.Mask" "F.Paste")
			(net "HPDB_HSC_PWRGD_ISO_R")
		)
		(pad "T13" smd circle
			(at 1.199896 3.599942 90)
			(size 0.4064 0.4064)
			(layers "F.Cu" "F.Mask" "F.Paste")
			(net "GPU_3V3IO_RSVD1_FFU_ISO_R")
		)
		(pad "T14" smd circle
			(at 1.999996 3.599942 90)
			(size 0.4064 0.4064)
			(layers "F.Cu" "F.Mask" "F.Paste")
			(net "RST_PERST_CPU0_SWB_N")
		)
		(pad "T15" smd circle
			(at 2.800096 3.599942 90)
			(size 0.4064 0.4064)
			(layers "F.Cu" "F.Mask" "F.Paste")
			(net "GPU_FPGA_BOOT_EN_R")
		)
		(pad "T16" smd circle
			(at 3.599942 3.599942 90)
			(size 0.4064 0.4064)
			(layers "F.Cu" "F.Mask" "F.Paste")
			(net "FM_P5V_EN")
		)
		(pad "T17" smd circle
			(at 4.400042 3.599942 90)
			(size 0.4064 0.4064)
			(layers "F.Cu" "F.Mask" "F.Paste")
			(net "RST_RT_CPU0_P3_RESET_R2_N")
		)
		(pad "T18" smd circle
			(at 5.199888 3.599942 90)
			(size 0.4064 0.4064)
			(layers "F.Cu" "F.Mask" "F.Paste")
			(net "P12V_ALL_PWROK_R")
		)
		(pad "T19" smd circle
			(at 5.999988 3.599942 90)
			(size 0.4064 0.4064)
			(layers "F.Cu" "F.Mask" "F.Paste")
			(net "RST_RT_CPU0_P3_PERST_R2_N")
		)
		(pad "T20" smd circle
			(at 6.800088 3.599942 90)
			(size 0.4064 0.4064)
			(layers "F.Cu" "F.Mask" "F.Paste")
			(net "SCM_IRQ_1V8_R_N")
		)
		(pad "T21" smd circle
			(at 7.599934 3.599942 90)
			(size 0.4064 0.4064)
			(layers "F.Cu" "F.Mask" "F.Paste")
			(net "ESPI_CPU0_R1_D0")
		)
		(pad "T22" smd circle
			(at 8.400034 3.599942 90)
			(size 0.4064 0.4064)
			(layers "F.Cu" "F.Mask" "F.Paste")
			(net "RST_ESPI_CPU0_RSTOUT_R_N")
		)
		(pad "U1" smd circle
			(at -8.400034 4.400042 90)
			(size 0.4064 0.4064)
			(layers "F.Cu" "F.Mask" "F.Paste")
			(net "FM_CPU0_SP5R3")
		)
		(pad "U2" smd circle
			(at -7.599934 4.400042 90)
			(size 0.4064 0.4064)
			(layers "F.Cu" "F.Mask" "F.Paste")
			(net "FM_CPU0_SP5R4")
		)
		(pad "U3" smd circle
			(at -6.800088 4.400042 90)
			(size 0.4064 0.4064)
			(layers "F.Cu" "F.Mask" "F.Paste")
			(net "E1S_0_PRSNT_R_N")
		)
		(pad "U4" smd circle
			(at -5.999988 4.400042 90)
			(size 0.4064 0.4064)
			(layers "F.Cu" "F.Mask" "F.Paste")
			(net "PWRGD_P5V_AUX_R3")
		)
		(pad "U5" smd circle
			(at -5.199888 4.400042 90)
			(size 0.4064 0.4064)
			(layers "F.Cu" "F.Mask" "F.Paste")
			(net "FM_LED_PWRGD_PVDDCR_CPU0_P0")
		)
		(pad "U6" smd circle
			(at -4.400042 4.400042 90)
			(size 0.4064 0.4064)
			(layers "F.Cu" "F.Mask" "F.Paste")
			(net "FM_PWRGD_PVDDIO_P0")
		)
		(pad "U7" smd circle
			(at -3.599942 4.400042 90)
			(size 0.4064 0.4064)
			(layers "F.Cu" "F.Mask" "F.Paste")
			(net "FM_UART_LS_EN")
		)
		(pad "U8" smd circle
			(at -2.800096 4.400042 90)
			(size 0.4064 0.4064)
			(layers "F.Cu" "F.Mask" "F.Paste")
			(net "FM_FPGA_DEBUG_SW_SPARE")
		)
		(pad "U9" smd circle
			(at -1.999996 4.400042 90)
			(size 0.4064 0.4064)
			(layers "F.Cu" "F.Mask" "F.Paste")
			(net "FM_PWRGD_P1V8_RETIMER_CPU1")
		)
		(pad "U10" smd circle
			(at -1.199896 4.400042 90)
			(size 0.4064 0.4064)
			(layers "F.Cu" "F.Mask" "F.Paste")
			(net "P12V_E1S_0_PWRGD")
		)
		(pad "U11" smd circle
			(at -0.40005 4.400042 90)
			(size 0.4064 0.4064)
			(layers "F.Cu" "F.Mask" "F.Paste")
			(net "P3V3_E1S_PWRGD_0_R")
		)
		(pad "U12" smd circle
			(at 0.40005 4.400042 90)
			(size 0.4064 0.4064)
			(layers "F.Cu" "F.Mask" "F.Paste")
			(net "Net_19")
		)
		(pad "U13" smd circle
			(at 1.199896 4.400042 90)
			(size 0.4064 0.4064)
			(layers "F.Cu" "F.Mask" "F.Paste")
			(net "HGX_DETECT_N_R")
		)
		(pad "U14" smd circle
			(at 1.999996 4.400042 90)
			(size 0.4064 0.4064)
			(layers "F.Cu" "F.Mask" "F.Paste")
			(net "RST_PERST_CPU1_SWB_N")
		)
		(pad "U15" smd circle
			(at 2.800096 4.400042 90)
			(size 0.4064 0.4064)
			(layers "F.Cu" "F.Mask" "F.Paste")
			(net "RST_BMC_FROM_SWB_ISO_R_N")
		)
		(pad "U16" smd circle
			(at 3.599942 4.400042 90)
			(size 0.4064 0.4064)
			(layers "F.Cu" "F.Mask" "F.Paste")
			(net "FM_NCSI_OCP_V3_2_R_OE")
		)
		(pad "U17" smd circle
			(at 4.400042 4.400042 90)
			(size 0.4064 0.4064)
			(layers "F.Cu" "F.Mask" "F.Paste")
			(net "FM_CPU0_FORCE_SELFREFRESH")
		)
		(pad "U18" smd circle
			(at 5.199888 4.400042 90)
			(size 0.4064 0.4064)
			(layers "F.Cu" "F.Mask" "F.Paste")
			(net "FM_PLD_CPU0_PRSNT_HDT")
		)
		(pad "U19" smd circle
			(at 5.999988 4.400042 90)
			(size 0.4064 0.4064)
			(layers "F.Cu" "F.Mask" "F.Paste")
			(net "FM_SPD_CPU0_SWITCH_CTRL_R_N")
		)
		(pad "U20" smd circle
			(at 6.800088 4.400042 90)
			(size 0.4064 0.4064)
			(layers "F.Cu" "F.Mask" "F.Paste")
			(net "BMC_JTAG_SEL_R")
		)
		(pad "U21" smd circle
			(at 7.599934 4.400042 90)
			(size 0.4064 0.4064)
			(layers "F.Cu" "F.Mask" "F.Paste")
			(net "FM_BIOS_POST_CMPLT_BUF_R_N")
		)
		(pad "U22" smd circle
			(at 8.400034 4.400042 90)
			(size 0.4064 0.4064)
			(layers "F.Cu" "F.Mask" "F.Paste")
			(net "FM_HDT_HDR_RESET_N")
		)
		(pad "V1" smd circle
			(at -8.400034 5.199888 90)
			(size 0.4064 0.4064)
			(layers "F.Cu" "F.Mask" "F.Paste")
			(net "FM_PRSNT_CPU0_R_N")
		)
		(pad "V2" smd circle
			(at -7.599934 5.199888 90)
			(size 0.4064 0.4064)
			(layers "F.Cu" "F.Mask" "F.Paste")
			(net "GND")
		)
		(pad "V3" smd circle
			(at -6.800088 5.199888 90)
			(size 0.4064 0.4064)
			(layers "F.Cu" "F.Mask" "F.Paste")
			(net "P3V3_AUX")
		)
		(pad "V4" smd circle
			(at -5.999988 5.199888 90)
			(size 0.4064 0.4064)
			(layers "F.Cu" "F.Mask" "F.Paste")
			(net "FM_LED_PWRGD_PVDDCR_SOC_P0")
		)
		(pad "V5" smd circle
			(at -5.199888 5.199888 90)
			(size 0.4064 0.4064)
			(layers "F.Cu" "F.Mask" "F.Paste")
			(net "FM_PRSNT_CPU1_R_N")
		)
		(pad "V6" smd circle
			(at -4.400042 5.199888 90)
			(size 0.4064 0.4064)
			(layers "F.Cu" "F.Mask" "F.Paste")
			(net "FM_PVDDIO_P0_EN")
		)
		(pad "V7" smd circle
			(at -3.599942 5.199888 90)
			(size 0.4064 0.4064)
			(layers "F.Cu" "F.Mask" "F.Paste")
			(net "GPU_FPGA_RST_N")
		)
		(pad "V8" smd circle
			(at -2.800096 5.199888 90)
			(size 0.4064 0.4064)
			(layers "F.Cu" "F.Mask" "F.Paste")
			(net "PVDD18_S5_P1_R_EN")
		)
	)
)
